#ISCELL
  mstr_symbols intel_corp_bpage *
  *
#ISCELL
  mstr_standard offpage *
  page134_i1
#CELL
  mstr_discrete res *
  page134_i11
#ISCELL
  mstr_symbols gnd *
  page134_i12
#ISCELL
  mstr_standard offpage *
  page134_i13
#CELL
  mstr_discrete fet_n *
  page134_i14
#CELL
  mstr_discrete fet_n *
  page134_i15
#ISCELL
  mstr_symbols p3v3_stby *
  page134_i2
#CELL
  mstr_discrete res *
  page134_i3
#ISCELL
  mstr_standard offpage *
  page134_i5
#ISCELL
  mstr_standard offpage *
  page134_i6
#ISCELL
  mstr_standard offpage *
  page134_i7
#ISCELL
  mstr_symbols p1v05_pch_stby *
  page134_i8
#CELL
  mstr_discrete res *
  page134_i9
